(kicad_pcb
	(version 20241229)
	(generator "pcbnew")
	(generator_version "9.0")
	(general
		(thickness 1.711)
		(legacy_teardrops no)
	)
	(paper "A4")
	(title_block
		(title "Antmicro Baseboard for Jetson AGX Thor")
		(date "2026-02-18")
		(rev "1.1.0")
		(company "Antmicro Ltd")
		(comment 1 "www.antmicro.com")
		(comment 9 "footprints 373-375 of 1170")
	)
	(layers
		(0 "F.Cu" signal)
		(4 "In1.Cu" signal)
		(6 "In2.Cu" signal)
		(8 "In3.Cu" signal)
		(10 "In4.Cu" jumper)
		(12 "In5.Cu" signal)
		(14 "In6.Cu" signal)
		(16 "In7.Cu" signal)
		(18 "In8.Cu" signal)
		(2 "B.Cu" signal)
		(9 "F.Adhes" user "F.Adhesive")
		(11 "B.Adhes" user "B.Adhesive")
		(13 "F.Paste" user)
		(15 "B.Paste" user)
		(5 "F.SilkS" user "F.Silkscreen")
		(7 "B.SilkS" user "B.Silkscreen")
		(1 "F.Mask" user)
		(3 "B.Mask" user)
		(17 "Dwgs.User" user "User.Drawings")
		(19 "Cmts.User" user "User.Comments")
		(21 "Eco1.User" user "User.Eco1")
		(23 "Eco2.User" user "User.Eco2")
		(25 "Edge.Cuts" user)
		(27 "Margin" user)
		(31 "F.CrtYd" user "F.Courtyard")
		(29 "B.CrtYd" user "B.Courtyard")
		(35 "F.Fab" user)
		(33 "B.Fab" user)
	)
	(footprint "antmicro-footprints:R_0402_1005Metric"
		(layer "F.Cu")
		(at 96.45 56.87)
		(descr "Resistor SMD 0402")
		(tags "resistor SMD 0402")
		(property "Reference" "R45"
			(at -3 0.33 0)
			(layer "F.SilkS")
			(effects
				(font
					(size 0.7 0.7)
					(thickness 0.15)
				)
				(justify left bottom)
			)
		)
		(property "Value" "R_3k92_0402"
			(at -1.011843 1.772047 0)
			(layer "F.Fab")
			(effects
				(font
					(size 0.7 0.7)
					(thickness 0.15)
				)
				(justify left bottom)
			)
		)
		(property "Datasheet" "https://www.bourns.com/docs/product-datasheets/cr.pdf"
			(at 0 0 0)
			(layer "F.Fab")
			(hide yes)
			(effects
				(font
					(size 1.27 1.27)
					(thickness 0.15)
				)
			)
		)
		(property "Description" "SMD Chip Resistor, 3.92 kohm, ± 1%, 100 mW, 0402 [1005 Metric], Thick Film, Precision"
			(at 0 0 0)
			(layer "F.Fab")
			(hide yes)
			(effects
				(font
					(size 1.27 1.27)
					(thickness 0.15)
				)
			)
		)
		(property "MPN" "CR0402-FX-3921GLF"
			(at 0 0 0)
			(unlocked yes)
			(layer "F.Fab")
			(hide yes)
			(effects
				(font
					(size 1 1)
					(thickness 0.15)
				)
			)
		)
		(property "Manufacturer" "Bourns"
			(at 0 0 0)
			(unlocked yes)
			(layer "F.Fab")
			(hide yes)
			(effects
				(font
					(size 1 1)
					(thickness 0.15)
				)
			)
		)
		(property "License" "Apache-2.0"
			(at 0 0 0)
			(unlocked yes)
			(layer "F.Fab")
			(hide yes)
			(effects
				(font
					(size 1 1)
					(thickness 0.15)
				)
			)
		)
		(property "Author" "Antmicro"
			(at 0 0 0)
			(unlocked yes)
			(layer "F.Fab")
			(hide yes)
			(effects
				(font
					(size 1 1)
					(thickness 0.15)
				)
			)
		)
		(property "Val" "3k92"
			(at 0 0 0)
			(unlocked yes)
			(layer "F.Fab")
			(hide yes)
			(effects
				(font
					(size 1 1)
					(thickness 0.15)
				)
			)
		)
		(property "Tolerance" "1%"
			(at 0 0 0)
			(unlocked yes)
			(layer "F.Fab")
			(hide yes)
			(effects
				(font
					(size 1 1)
					(thickness 0.15)
				)
			)
		)
		(sheetname "/SoM_Power/")
		(sheetfile "som_power.kicad_sch")
		(attr smd)
		(fp_rect
			(start -0.925 -0.47)
			(end 0.925 0.47)
			(stroke
				(width 0.05)
				(type default)
			)
			(fill no)
			(layer "F.CrtYd")
		)
		(fp_rect
			(start -0.5 -0.25)
			(end 0.5 0.25)
			(stroke
				(width 0.15)
				(type solid)
			)
			(fill no)
			(layer "F.Fab")
		)
		(fp_text user "${REFERENCE}"
			(at -0.95 3.168 0)
			(layer "F.Fab")
			(effects
				(font
					(size 0.7 0.7)
					(thickness 0.15)
				)
				(justify left bottom)
			)
		)
		(fp_text user "License: Apache-2.0"
			(at -0.95 5.169 0)
			(layer "F.Fab")
			(effects
				(font
					(size 0.7 0.7)
					(thickness 0.15)
				)
				(justify left bottom)
			)
		)
		(fp_text user "Author: Antmicro"
			(at -0.95 4.169 0)
			(layer "F.Fab")
			(effects
				(font
					(size 0.7 0.7)
					(thickness 0.15)
				)
				(justify left bottom)
			)
		)
		(pad "1" smd roundrect
			(at -0.48 0)
			(size 0.59 0.64)
			(layers "F.Cu" "F.Mask" "F.Paste")
			(roundrect_rratio 0.25)
			(net 1380 "Net-(U3-DIV)")
			(pintype "passive")
		)
		(pad "2" smd roundrect
			(at 0.48 0)
			(size 0.59 0.64)
			(layers "F.Cu" "F.Mask" "F.Paste")
			(roundrect_rratio 0.25)
			(net 4 "+3V3_AON")
			(pintype "passive")
		)
	)
	(footprint "antmicro-footprints:C_0402_1005Metric"
		(layer "F.Cu")
		(at 130.549999 59.47)
		(descr "Capacitor SMD 0402")
		(tags "capacitor SMD 0402")
		(property "Reference" "C377"
			(at 0.920001 0.01 0)
			(layer "F.SilkS")
			(effects
				(font
					(size 0.7 0.7)
					(thickness 0.15)
				)
				(justify left bottom)
			)
		)
		(property "Value" "C_100n_0402"
			(at -1.022927 2.155213 0)
			(layer "F.Fab")
			(effects
				(font
					(size 0.7 0.7)
					(thickness 0.15)
				)
				(justify left bottom)
			)
		)
		(property "Datasheet" "https://www.murata.com/products/productdetail?partno=GRM155R61H104KE14%23"
			(at 0 0 0)
			(layer "F.Fab")
			(hide yes)
			(effects
				(font
					(size 1.27 1.27)
					(thickness 0.15)
				)
			)
		)
		(property "Description" "SMD Multilayer Ceramic Capacitor, 0.1 µF, 50 V, 0402 [1005 Metric], ± 10%, X5R, GRM Series"
			(at 0 0 0)
			(layer "F.Fab")
			(hide yes)
			(effects
				(font
					(size 1.27 1.27)
					(thickness 0.15)
				)
			)
		)
		(property "Manufacturer" "Murata"
			(at 0 0 0)
			(unlocked yes)
			(layer "F.Fab")
			(hide yes)
			(effects
				(font
					(size 1 1)
					(thickness 0.15)
				)
			)
		)
		(property "MPN" "GRM155R61H104KE14D"
			(at 0 0 0)
			(unlocked yes)
			(layer "F.Fab")
			(hide yes)
			(effects
				(font
					(size 1 1)
					(thickness 0.15)
				)
			)
		)
		(property "Val" "100n"
			(at 0 0 0)
			(unlocked yes)
			(layer "F.Fab")
			(hide yes)
			(effects
				(font
					(size 1 1)
					(thickness 0.15)
				)
			)
		)
		(property "License" "Apache-2.0"
			(at 0 0 0)
			(unlocked yes)
			(layer "F.Fab")
			(hide yes)
			(effects
				(font
					(size 1 1)
					(thickness 0.15)
				)
			)
		)
		(property "Author" "Antmicro"
			(at 0 0 0)
			(unlocked yes)
			(layer "F.Fab")
			(hide yes)
			(effects
				(font
					(size 1 1)
					(thickness 0.15)
				)
			)
		)
		(property "Voltage" "50V"
			(at 0 0 0)
			(unlocked yes)
			(layer "F.Fab")
			(hide yes)
			(effects
				(font
					(size 1 1)
					(thickness 0.15)
				)
			)
		)
		(property "Dielectric" "X5R"
			(at 0 0 0)
			(unlocked yes)
			(layer "F.Fab")
			(hide yes)
			(effects
				(font
					(size 1 1)
					(thickness 0.15)
				)
			)
		)
		(sheetname "/DCDC/")
		(sheetfile "dcdc.kicad_sch")
		(attr smd)
		(fp_poly
			(pts
				(xy -0.925 -0.47) (xy 0.925 -0.47) (xy 0.925 0.47) (xy -0.925 0.47)
			)
			(stroke
				(width 0.05)
				(type default)
			)
			(fill no)
			(layer "F.CrtYd")
		)
		(fp_line
			(start -0.494 -0.25)
			(end 0.504 -0.25)
			(stroke
				(width 0.15)
				(type solid)
			)
			(layer "F.Fab")
		)
		(fp_line
			(start -0.494 0.248)
			(end -0.494 -0.25)
			(stroke
				(width 0.15)
				(type solid)
			)
			(layer "F.Fab")
		)
		(fp_line
			(start 0.504 -0.25)
			(end 0.504 0.248)
			(stroke
				(width 0.15)
				(type solid)
			)
			(layer "F.Fab")
		)
		(fp_line
			(start 0.504 0.248)
			(end -0.494 0.248)
			(stroke
				(width 0.15)
				(type solid)
			)
			(layer "F.Fab")
		)
		(fp_text user "${REFERENCE}"
			(at -0.939 4.599 0)
			(layer "F.Fab")
			(effects
				(font
					(size 0.7 0.7)
					(thickness 0.15)
				)
				(justify left bottom)
			)
		)
		(fp_text user "License: Apache-2.0"
			(at -0.939 5.799 0)
			(layer "F.Fab")
			(effects
				(font
					(size 0.7 0.7)
					(thickness 0.15)
				)
				(justify left bottom)
			)
		)
		(fp_text user "Author: Antmicro"
			(at -0.939 3.399 0)
			(layer "F.Fab")
			(effects
				(font
					(size 0.7 0.7)
					(thickness 0.15)
				)
				(justify left bottom)
			)
		)
		(pad "1" smd roundrect
			(at -0.48 0)
			(size 0.59 0.64)
			(layers "F.Cu" "F.Mask" "F.Paste")
			(roundrect_rratio 0.25)
			(net 1277 "/DCDC/5V_{AON}_PHASE")
			(pintype "passive")
		)
		(pad "2" smd roundrect
			(at 0.48 0)
			(size 0.59 0.64)
			(layers "F.Cu" "F.Mask" "F.Paste")
			(roundrect_rratio 0.25)
			(net 1276 "/DCDC/5V_{AON}_BOOT")
			(pintype "passive")
		)
	)
	(footprint "antmicro-footprints:MLP44-24L_4x4x0.75mm"
		(layer "F.Cu")
		(at 181 111)
		(property "Reference" "U12"
			(at 0.6 3.456 0)
			(layer "F.SilkS")
			(effects
				(font
					(size 0.7 0.7)
					(thickness 0.15)
				)
				(justify left bottom)
			)
		)
		(property "Value" "SIC437AED-T1-GE3"
			(at -2.7 3.6 0)
			(layer "F.Fab")
			(effects
				(font
					(size 0.7 0.7)
					(thickness 0.15)
				)
				(justify left bottom)
			)
		)
		(property "Datasheet" "https://www.vishay.com/docs/75921/sic437.pdf"
			(at 0 0 0)
			(layer "F.Fab")
			(hide yes)
			(effects
				(font
					(size 1.27 1.27)
					(thickness 0.15)
				)
			)
		)
		(property "Description" "DC/DC Buck Step Down Regulator Adjustable, 4.5-28V In, 0.6V to 20V/12A Out, 1MHz, PowerPAK MLP44-24"
			(at 0 0 0)
			(layer "F.Fab")
			(hide yes)
			(effects
				(font
					(size 1.27 1.27)
					(thickness 0.15)
				)
			)
		)
		(property "Manufacturer" "Vishay"
			(at 0 0 0)
			(unlocked yes)
			(layer "F.Fab")
			(hide yes)
			(effects
				(font
					(size 1 1)
					(thickness 0.15)
				)
			)
		)
		(property "MPN" "SIC437AED-T1-GE3"
			(at 0 0 0)
			(unlocked yes)
			(layer "F.Fab")
			(hide yes)
			(effects
				(font
					(size 1 1)
					(thickness 0.15)
				)
			)
		)
		(property "Author" "Antmicro"
			(at 0 0 0)
			(unlocked yes)
			(layer "F.Fab")
			(hide yes)
			(effects
				(font
					(size 1 1)
					(thickness 0.15)
				)
			)
		)
		(property "License" "Apache-2.0"
			(at 0 0 0)
			(unlocked yes)
			(layer "F.Fab")
			(hide yes)
			(effects
				(font
					(size 1 1)
					(thickness 0.15)
				)
			)
		)
		(sheetname "/DCDC/")
		(sheetfile "dcdc.kicad_sch")
		(attr smd)
		(net_tie_pad_groups "1,2,26" "3,4,27" "5,6,7,8,9")
		(fp_line
			(start -2.11 -1.38)
			(end -2.11 -2.1)
			(stroke
				(width 0.15)
				(type solid)
			)
			(layer "F.SilkS")
		)
		(fp_line
			(start -2.11 2.11)
			(end -2.11 1.39)
			(stroke
				(width 0.15)
				(type solid)
			)
			(layer "F.SilkS")
		)
		(fp_line
			(start -1.89 -2.1)
			(end -2.11 -2.1)
			(stroke
				(width 0.15)
				(type solid)
			)
			(layer "F.SilkS")
		)
		(fp_line
			(start -1.89 2.11)
			(end -2.11 2.11)
			(stroke
				(width 0.15)
				(type solid)
			)
			(layer "F.SilkS")
		)
		(fp_line
			(start 1.44 2.11)
			(end 2.11 2.11)
			(stroke
				(width 0.15)
				(type solid)
			)
			(layer "F.SilkS")
		)
		(fp_line
			(start 1.89 -2.11)
			(end 2.11 -2.11)
			(stroke
				(width 0.15)
				(type solid)
			)
			(layer "F.SilkS")
		)
		(fp_line
			(start 2.11 -2.11)
			(end 2.11 -1.69)
			(stroke
				(width 0.15)
				(type solid)
			)
			(layer "F.SilkS")
		)
		(fp_line
			(start 2.11 2.11)
			(end 2.11 1.84)
			(stroke
				(width 0.15)
				(type solid)
			)
			(layer "F.SilkS")
		)
		(fp_circle
			(center -2.25 -1.15)
			(end -2.2 -1.15)
			(stroke
				(width 0.15)
				(type solid)
			)
			(fill yes)
			(layer "F.SilkS")
		)
		(fp_line
			(start -2.55 -2.55)
			(end 2.55 -2.55)
			(stroke
				(width 0.05)
				(type solid)
			)
			(layer "F.CrtYd")
		)
		(fp_line
			(start -2.55 2.55)
			(end -2.55 -2.55)
			(stroke
				(width 0.05)
				(type solid)
			)
			(layer "F.CrtYd")
		)
		(fp_line
			(start 2.55 -2.55)
			(end 2.55 2.55)
			(stroke
				(width 0.05)
				(type solid)
			)
			(layer "F.CrtYd")
		)
		(fp_line
			(start 2.55 2.55)
			(end -2.55 2.55)
			(stroke
				(width 0.05)
				(type solid)
			)
			(layer "F.CrtYd")
		)
		(fp_line
			(start -2 -1)
			(end -2 2)
			(stroke
				(width 0.15)
				(type solid)
			)
			(layer "F.Fab")
		)
		(fp_line
			(start -2 2)
			(end 2 2)
			(stroke
				(width 0.15)
				(type solid)
			)
			(layer "F.Fab")
		)
		(fp_line
			(start -1 -2)
			(end -2 -1)
			(stroke
				(width 0.15)
				(type solid)
			)
			(layer "F.Fab")
		)
		(fp_line
			(start 2 -2)
			(end -1 -2)
			(stroke
				(width 0.15)
				(type solid)
			)
			(layer "F.Fab")
		)
		(fp_line
			(start 2 2)
			(end 2 -2)
			(stroke
				(width 0.15)
				(type solid)
			)
			(layer "F.Fab")
		)
		(fp_text user "License: Apache-2.0"
			(at -2.7 5.6 0)
			(layer "F.Fab")
			(effects
				(font
					(size 0.7 0.7)
					(thickness 0.15)
				)
				(justify left bottom)
			)
		)
		(fp_text user "${REFERENCE}"
			(at -2.7 6.8 0)
			(layer "F.Fab")
			(effects
				(font
					(size 0.7 0.7)
					(thickness 0.15)
				)
				(justify left bottom)
			)
		)
		(fp_text user "Author: Antmicro"
			(at -2.7 8 0)
			(layer "F.Fab")
			(effects
				(font
					(size 0.7 0.7)
					(thickness 0.15)
				)
				(justify left bottom)
			)
		)
		(pad "1" smd roundrect
			(at -1.94 -0.825 90)
			(size 0.3 0.725)
			(layers "F.Cu" "F.Mask" "F.Paste")
			(roundrect_rratio 0.25)
			(net 13 "VCC")
			(pinfunction "V_{IN}")
			(pintype "power_in")
		)
		(pad "2" smd roundrect
			(at -1.94 -0.375 90)
			(size 0.3 0.725)
			(layers "F.Cu" "F.Mask" "F.Paste")
			(roundrect_rratio 0.25)
			(net 13 "VCC")
			(pinfunction "V_{IN}")
			(pintype "passive")
		)
		(pad "3" smd roundrect
			(at -1.94 0.525 90)
			(size 0.3 0.725)
			(layers "F.Cu" "F.Mask" "F.Paste")
			(roundrect_rratio 0.25)
			(net 1 "GND")
			(pinfunction "P_{GND}")
			(pintype "passive")
		)
		(pad "4" smd roundrect
			(at -1.94 0.975 90)
			(size 0.3 0.725)
			(layers "F.Cu" "F.Mask" "F.Paste")
			(roundrect_rratio 0.25)
			(net 1 "GND")
			(pinfunction "P_{GND}")
			(pintype "passive")
		)
		(pad "5" smd custom
			(at -1.475 1.94)
			(size 0.3 0.3)
			(layers "F.Cu" "F.Mask" "F.Paste")
			(net 1181 "/DCDC/5V_SW")
			(pinfunction "SW")
			(pintype "passive")
			(options
				(clearance outline)
				(anchor circle)
			)
			(primitives
				(gr_poly
					(pts
						(xy -0.15 -0.2875) (xy -0.144291 -0.316201) (xy -0.128033 -0.340533) (xy -0.103701 -0.356791)
						(xy -0.075 -0.3625) (xy 0.075 -0.3625) (xy 0.103701 -0.356791) (xy 0.128033 -0.340533) (xy 0.144291 -0.316201)
						(xy 0.15 -0.2875) (xy 0.15 0.2875) (xy 0.144291 0.316201) (xy 0.128033 0.340533) (xy 0.103701 0.356791)
						(xy 0.075 0.3625) (xy -0.075 0.3625) (xy -0.103701 0.356791) (xy -0.128033 0.340533) (xy -0.144291 0.316201)
						(xy -0.15 0.2875)
					)
					(width 0)
					(fill yes)
				)
				(gr_poly
					(pts
						(xy -0.15 -0.3625) (xy 2.2 -0.3625) (xy 2.2 -0.0875) (xy -0.15 -0.0875)
					)
					(width 0)
					(fill yes)
				)
			)
		)
		(pad "6" smd roundrect
			(at -1.025 1.94)
			(size 0.3 0.725)
			(layers "F.Cu" "F.Mask" "F.Paste")
			(roundrect_rratio 0.25)
			(net 1181 "/DCDC/5V_SW")
			(pinfunction "SW")
			(pintype "passive")
		)
		(pad "7" smd roundrect
			(at -0.575 1.94)
			(size 0.3 0.725)
			(layers "F.Cu" "F.Mask" "F.Paste")
			(roundrect_rratio 0.25)
			(net 1181 "/DCDC/5V_SW")
			(pinfunction "SW")
			(pintype "passive")
		)
		(pad "8" smd roundrect
			(at 0.125 1.94)
			(size 0.3 0.725)
			(layers "F.Cu" "F.Mask" "F.Paste")
			(roundrect_rratio 0.25)
			(net 1181 "/DCDC/5V_SW")
			(pinfunction "SW")
			(pintype "passive")
		)
		(pad "9" smd roundrect
			(at 0.575 1.94)
			(size 0.3 0.725)
			(layers "F.Cu" "F.Mask" "F.Paste")
			(roundrect_rratio 0.25)
			(net 1181 "/DCDC/5V_SW")
			(pinfunction "SW")
			(pintype "passive")
		)
		(pad "10" smd roundrect
			(at 1.025 1.935)
			(size 0.3 0.725)
			(layers "F.Cu" "F.Mask" "F.Paste")
			(roundrect_rratio 0.25)
			(net 1054 "unconnected-(U12-GL-Pad10)_1")
			(pinfunction "GL")
			(pintype "passive+no_connect")
		)
		(pad "11" smd roundrect
			(at 1.94 1.425 90)
			(size 0.3 0.725)
			(layers "F.Cu" "F.Mask" "F.Paste")
			(roundrect_rratio 0.25)
			(net 1053 "unconnected-(U12-GL-Pad10)")
			(pinfunction "GL")
			(pintype "passive+no_connect")
		)
		(pad "12" smd roundrect
			(at 1.94 0.975 90)
			(size 0.3 0.725)
			(layers "F.Cu" "F.Mask" "F.Paste")
			(roundrect_rratio 0.25)
			(net 23 "/DCDC/5V_VDRV")
			(pinfunction "V_{DRV}")
			(pintype "passive")
		)
		(pad "13" smd roundrect
			(at 1.94 0.525 90)
			(size 0.3 0.725)
			(layers "F.Cu" "F.Mask" "F.Paste")
			(roundrect_rratio 0.25)
			(net 1 "GND")
			(pinfunction "P_{GND}")
			(pintype "power_in")
		)
		(pad "14" smd roundrect
			(at 1.94 0.075 90)
			(size 0.3 0.725)
			(layers "F.Cu" "F.Mask" "F.Paste")
			(roundrect_rratio 0.25)
			(net 1322 "unconnected-(U12-P_{GOOD}-Pad14)")
			(pinfunction "P_{GOOD}")
			(pintype "output+no_connect")
		)
		(pad "15" smd roundrect
			(at 1.94 -0.375 90)
			(size 0.3 0.725)
			(layers "F.Cu" "F.Mask" "F.Paste")
			(roundrect_rratio 0.25)
			(net 18 "/DCDC/5V_VDD")
			(pinfunction "V_{DD}")
			(pintype "passive")
		)
		(pad "16" smd roundrect
			(at 1.94 -0.825 90)
			(size 0.3 0.725)
			(layers "F.Cu" "F.Mask" "F.Paste")
			(roundrect_rratio 0.25)
			(net 1 "GND")
			(pinfunction "A_{GND}")
			(pintype "power_in")
		)
		(pad "17" smd roundrect
			(at 1.94 -1.275 90)
			(size 0.3 0.725)
			(layers "F.Cu" "F.Mask" "F.Paste")
			(roundrect_rratio 0.25)
			(net 1217 "/DCDC/5V_FB")
			(pinfunction "FB")
			(pintype "passive")
		)
		(pad "18" smd roundrect
			(at 1.475 -1.94)
			(size 0.3 0.725)
			(layers "F.Cu" "F.Mask" "F.Paste")
			(roundrect_rratio 0.25)
			(net 253 "/DCDC/5V_OUT")
			(pinfunction "V_{OUT}")
			(pintype "passive")
		)
		(pad "19" smd roundrect
			(at 1.025 -1.94)
			(size 0.3 0.725)
			(layers "F.Cu" "F.Mask" "F.Paste")
			(roundrect_rratio 0.25)
			(net 1293 "/DCDC/CARRIER_PWR_ON")
			(pinfunction "EN")
			(pintype "input")
		)
		(pad "20" smd roundrect
			(at 0.575 -1.94)
			(size 0.3 0.725)
			(layers "F.Cu" "F.Mask" "F.Paste")
			(roundrect_rratio 0.25)
			(net 1215 "/DCDC/5V_MODE2")
			(pinfunction "MODE2")
			(pintype "input")
		)
		(pad "21" smd roundrect
			(at 0.125 -1.94)
			(size 0.3 0.725)
			(layers "F.Cu" "F.Mask" "F.Paste")
			(roundrect_rratio 0.25)
			(net 1212 "/DCDC/5V_MODE1")
			(pinfunction "MODE1")
			(pintype "input")
		)
		(pad "22" smd roundrect
			(at -0.575 -1.94)
			(size 0.3 0.725)
			(layers "F.Cu" "F.Mask" "F.Paste")
			(roundrect_rratio 0.25)
			(net 13 "VCC")
			(pinfunction "V_{IN}")
			(pintype "passive")
		)
		(pad "23" smd roundrect
			(at -1.025 -1.94)
			(size 0.3 0.725)
			(layers "F.Cu" "F.Mask" "F.Paste")
			(roundrect_rratio 0.25)
			(net 25 "/DCDC/5V_BOOT")
			(pinfunction "BOOT")
			(pintype "passive")
		)
		(pad "24" smd roundrect
			(at -1.475 -1.94)
			(size 0.3 0.725)
			(layers "F.Cu" "F.Mask" "F.Paste")
			(roundrect_rratio 0.25)
			(net 26 "/DCDC/5V_PHASE")
			(pinfunction "PHASE")
			(pintype "passive")
		)
		(pad "25" smd rect
			(at 0.49 -0.75 180)
			(size 1.575 1.05)
			(layers "F.Cu" "F.Mask" "F.Paste")
			(net 1 "GND")
			(pinfunction "A_{GND}")
			(pintype "passive")
		)
		(pad "26" smd rect
			(at -1.175 -0.75 180)
			(size 1.15 1.05)
			(layers "F.Cu" "F.Mask" "F.Paste")
			(net 13 "VCC")
			(pinfunction "V_{IN}")
			(pintype "passive")
		)
		(pad "27" smd custom
			(at -0.75 0.775)
			(size 1 1)
			(layers "F.Cu" "F.Mask" "F.Paste")
			(net 1 "GND")
			(pinfunction "P_{GND}")
			(pintype "passive")
			(options
				(clearance outline)
				(anchor rect)
			)
			(primitives
				(gr_poly
					(pts
						(xy -1 0.5) (xy -1 -0.7) (xy 1.825 -0.7) (xy 1.825 -0.245) (xy 1.175 -0.245) (xy 1.175 0.5)
					)
					(width 0)
					(fill yes)
				)
			)
		)
		(pad "28" smd rect
			(at 0.985 0.99 180)
			(size 0.58 0.38)
			(layers "F.Cu" "F.Mask" "F.Paste")
			(net 1055 "unconnected-(U12-GL-Pad10)_2")
			(pinfunction "GL")
			(pintype "passive+no_connect")
		)
	)
)
